# S9S_MB_2U (Grand Teton) — schematic netlist excerpt (pin names and nets, part order shuffled) for the footprints in the layout excerpt that follows; sources: Cadence DE-HDL packaged netlist, KiCad conversion of 03242023_DA0F0TMBIJ0_F0T_Motherboard_J_brd_V01_OCP.brd

U312  TUSB211IRWBR  EMPTY  pkg X2QFN12_0-4_1-6X1-6  page 196
  D1M  = USB2_HUB_2_BUF_EXT_R_DN
  D1P  = USB2_HUB_2_BUF_EXT_R_DP
  TEST  = TP_USB_HUB_2_TEST
  CD  = TP_USB_HUB_2_CD
  RSTN  = PD_USB_HUB_2_RSTN
  EQ  = PD_USB_HUB_2_EQ
  D2P  = USB2_HUB_2_BUF_EXT_R_DP
  D2M  = USB2_HUB_2_BUF_EXT_R_DN
  ENA_HS  = TP_USB_HUB_2_ENA_HS
  GND  = GND
  VREG  = PD_USB_HUB_2_VREG
  VCC  = P3V3_AUX

C1916  Q_CAP  0.01UF 50V 10% X7R  pkg C0402  page 217 : A = VCC_PLD_CORE ; B = GND

(kicad_pcb
	(version 20260206)
	(generator "pcbnew")
	(generator_version "10.0")
	(general
		(thickness 1.6)
		(legacy_teardrops no)
	)
	(paper "A4")
	(title_block
		(title "03242023_DA0F0TMBIJ0_F0T_Motherboard_J_brd_V01_OCP.brd")
		(comment 1 "Grand Teton / footprints 5023-5024 of 6105")
	)
	(layers
		(0 "F.Cu" signal "TOP")
		(4 "In1.Cu" signal "GND")
		(6 "In2.Cu" signal "IN1")
		(8 "In3.Cu" signal "GND1")
		(10 "In4.Cu" signal "IN2")
		(12 "In5.Cu" signal "GND2")
		(14 "In6.Cu" signal "IN3")
		(16 "In7.Cu" signal "GND3")
		(18 "In8.Cu" signal "VCC")
		(20 "In9.Cu" signal "VCC1")
		(22 "In10.Cu" signal "GND4")
		(24 "In11.Cu" signal "IN4")
		(26 "In12.Cu" signal "GND5")
		(28 "In13.Cu" signal "IN5")
		(30 "In14.Cu" signal "GND6")
		(32 "In15.Cu" signal "IN6")
		(34 "In16.Cu" signal "GND7")
		(2 "B.Cu" signal "BOTTOM")
		(9 "F.Adhes" user "F.Adhesive")
		(11 "B.Adhes" user "B.Adhesive")
		(13 "F.Paste" user "Package Geometry/Pastemask Top")
		(15 "B.Paste" user "Package Geometry/Pastemask Bottom")
		(5 "F.SilkS" user "Ref Des/Silkscreen Top")
		(7 "B.SilkS" user "Ref Des/Silkscreen Bottom")
		(1 "F.Mask" user "Board Geometry/Soldermask Top")
		(3 "B.Mask" user "Board Geometry/Soldermask Bottom")
		(17 "Dwgs.User" user "User.Drawings")
		(19 "Cmts.User" user "User.Comments")
		(21 "Eco1.User" user "User.Eco1")
		(23 "Eco2.User" user "User.Eco2")
		(25 "Edge.Cuts" user "Board Geometry/Outline")
		(27 "Margin" user)
		(31 "F.CrtYd" user "Package Geometry/Place Bound Top")
		(29 "B.CrtYd" user "Package Geometry/Place Bound Bottom")
		(35 "F.Fab" user "Ref Des/Assembly Top")
		(33 "B.Fab" user "Ref Des/Assembly Bottom")
	)
	(footprint ""
		(layer "B.Cu")
		(at 178.1556 -114.17554 -90)
		(property "Reference" "C1916"
			(at 0 0 90)
			(layer "B.SilkS")
			(hide yes)
			(effects
				(font
					(size 1.27 1.27)
				)
				(justify mirror)
			)
		)
		(property "Value" ""
			(at 0 0 90)
			(layer "B.Fab")
			(effects
				(font
					(size 1.27 1.27)
				)
				(justify mirror)
			)
		)
		(duplicate_pad_numbers_are_jumpers no)
		(fp_line
			(start -0.69215 0.2921)
			(end 0.69215 0.2921)
			(stroke
				(width 0.1524)
				(type default)
			)
			(layer "B.SilkS")
		)
		(fp_line
			(start 0.69215 0.2921)
			(end 0.69215 -0.2921)
			(stroke
				(width 0.1524)
				(type default)
			)
			(layer "B.SilkS")
		)
		(fp_line
			(start -0.69215 -0.2921)
			(end -0.69215 0.2921)
			(stroke
				(width 0.1524)
				(type default)
			)
			(layer "B.SilkS")
		)
		(fp_line
			(start 0.69215 -0.2921)
			(end -0.69215 -0.2921)
			(stroke
				(width 0.1524)
				(type default)
			)
			(layer "B.SilkS")
		)
		(fp_line
			(start -0.51435 0.2794)
			(end 0.51435 0.2794)
			(stroke
				(width 0.1)
				(type default)
			)
			(layer "B.Fab")
		)
		(fp_line
			(start 0.51435 0.2794)
			(end 0.51435 -0.2794)
			(stroke
				(width 0.1)
				(type default)
			)
			(layer "B.Fab")
		)
		(fp_line
			(start -0.51435 -0.2794)
			(end -0.51435 0.2794)
			(stroke
				(width 0.1)
				(type default)
			)
			(layer "B.Fab")
		)
		(fp_line
			(start 0.51435 -0.2794)
			(end -0.51435 -0.2794)
			(stroke
				(width 0.1)
				(type default)
			)
			(layer "B.Fab")
		)
		(pad "1" smd circle
			(at 0.40005 0 90)
			(size 0 0)
			(layers "B.Cu" "B.Mask" "B.Paste")
			(net "VCC_PLD_CORE")
		)
		(pad "2" smd circle
			(at -0.40005 0 90)
			(size 0 0)
			(layers "B.Cu" "B.Mask" "B.Paste")
			(net "GND")
		)
		(zone
			(layer "B.Cu")
			(hatch none 0.5)
			(connect_pads
				(clearance 0)
			)
			(min_thickness 0.25)
			(keepout
				(tracks not_allowed)
				(vias allowed)
				(pads allowed)
				(copperpour not_allowed)
				(footprints allowed)
			)
			(placement
				(enabled no)
				(sheetname "")
			)
			(fill
				(thermal_gap 0.5)
				(thermal_bridge_width 0.5)
				(island_removal_mode 0)
			)
			(polygon
				(pts
					(xy 178.06797 -113.98504) (xy 178.009804 -114.07648) (xy 178.009804 -114.27587) (xy 178.06797 -114.36604)
					(xy 178.24323 -114.36604) (xy 178.30165 -114.27587) (xy 178.30165 -114.07648) (xy 178.243484 -113.98504)
				)
			)
		)
	)
	(footprint ""
		(layer "B.Cu")
		(at 140.6779 -28.429458 90)
		(property "Reference" "U312"
			(at 2.765298 5.54609 0)
			(unlocked yes)
			(layer "B.SilkS")
			(effects
				(font
					(size 0.7874 0.5842)
					(thickness 0.1524)
				)
				(justify left mirror)
			)
		)
		(property "Value" ""
			(at 0 0 90)
			(layer "B.Fab")
			(effects
				(font
					(size 1.27 1.27)
				)
				(justify mirror)
			)
		)
		(duplicate_pad_numbers_are_jumpers no)
		(fp_line
			(start 1.2446 -1.2446)
			(end 1.2446 -0.4318)
			(stroke
				(width 0.1524)
				(type default)
			)
			(layer "B.SilkS")
		)
		(fp_line
			(start -1.2446 -1.2446)
			(end 1.2446 -1.2446)
			(stroke
				(width 0.1524)
				(type default)
			)
			(layer "B.SilkS")
		)
		(fp_line
			(start -1.2446 -0.56896)
			(end -1.2446 -1.2446)
			(stroke
				(width 0.1524)
				(type default)
			)
			(layer "B.SilkS")
		)
		(fp_line
			(start 1.2446 0.54356)
			(end 1.2446 1.2446)
			(stroke
				(width 0.1524)
				(type default)
			)
			(layer "B.SilkS")
		)
		(fp_line
			(start 1.2446 1.2446)
			(end -1.2446 1.2446)
			(stroke
				(width 0.1524)
				(type default)
			)
			(layer "B.SilkS")
		)
		(fp_line
			(start -1.2446 1.2446)
			(end -1.2446 0.54864)
			(stroke
				(width 0.1524)
				(type default)
			)
			(layer "B.SilkS")
		)
		(fp_poly
			(pts
				(xy 1.377442 -0.400304) (xy 1.649476 -1.21666) (xy 2.193544 -0.672592)
			)
			(stroke
				(width 0)
				(type default)
			)
			(fill yes)
			(layer "B.SilkS")
		)
		(fp_line
			(start 0.824992 -0.824992)
			(end 0.824992 0.824992)
			(stroke
				(width 0.1)
				(type default)
			)
			(layer "B.Fab")
		)
		(fp_line
			(start -0.824992 -0.824992)
			(end 0.824992 -0.824992)
			(stroke
				(width 0.1)
				(type default)
			)
			(layer "B.Fab")
		)
		(fp_line
			(start 0.824992 0.824992)
			(end -0.824992 0.824992)
			(stroke
				(width 0.1)
				(type default)
			)
			(layer "B.Fab")
		)
		(fp_line
			(start -0.824992 0.824992)
			(end -0.824992 -0.824992)
			(stroke
				(width 0.1)
				(type default)
			)
			(layer "B.Fab")
		)
		(fp_poly
			(pts
				(xy 1.389634 -0.199898) (xy 2.159 0.184658) (xy 2.159 -0.584708)
			)
			(stroke
				(width 0)
				(type default)
			)
			(fill yes)
			(layer "B.Fab")
		)
		(pad "1" smd rect
			(at 0.700024 -0.199898)
			(size 0.1778 0.8128)
			(layers "B.Cu" "B.Mask" "B.Paste")
			(net "USB2_HUB_2_BUF_EXT_R_DN")
		)
		(pad "2" smd rect
			(at 0.700024 0.199898)
			(size 0.1778 0.8128)
			(layers "B.Cu" "B.Mask" "B.Paste")
			(net "USB2_HUB_2_BUF_EXT_R_DP")
		)
		(pad "3" smd rect
			(at 0.599948 0.8001 270)
			(size 0.1778 0.6096)
			(layers "B.Cu" "B.Mask" "B.Paste")
			(net "TP_USB_HUB_2_TEST")
		)
		(pad "4" smd rect
			(at 0.199898 0.8001 270)
			(size 0.1778 0.6096)
			(layers "B.Cu" "B.Mask" "B.Paste")
			(net "TP_USB_HUB_2_CD")
		)
		(pad "5" smd rect
			(at -0.199898 0.8001 270)
			(size 0.1778 0.6096)
			(layers "B.Cu" "B.Mask" "B.Paste")
			(net "PD_USB_HUB_2_RSTN")
		)
		(pad "6" smd rect
			(at -0.599948 0.8001 270)
			(size 0.1778 0.6096)
			(layers "B.Cu" "B.Mask" "B.Paste")
			(net "PD_USB_HUB_2_EQ")
		)
		(pad "7" smd rect
			(at -0.700024 0.199898)
			(size 0.1778 0.8128)
			(layers "B.Cu" "B.Mask" "B.Paste")
			(net "USB2_HUB_2_BUF_EXT_R_DP")
		)
		(pad "8" smd rect
			(at -0.700024 -0.199898)
			(size 0.1778 0.8128)
			(layers "B.Cu" "B.Mask" "B.Paste")
			(net "USB2_HUB_2_BUF_EXT_R_DN")
		)
		(pad "9" smd rect
			(at -0.599948 -0.8001 270)
			(size 0.1778 0.6096)
			(layers "B.Cu" "B.Mask" "B.Paste")
			(net "TP_USB_HUB_2_ENA_HS")
		)
		(pad "10" smd rect
			(at -0.199898 -0.8001 270)
			(size 0.1778 0.6096)
			(layers "B.Cu" "B.Mask" "B.Paste")
			(net "GND")
		)
		(pad "11" smd rect
			(at 0.199898 -0.8001 270)
			(size 0.1778 0.6096)
			(layers "B.Cu" "B.Mask" "B.Paste")
			(net "PD_USB_HUB_2_VREG")
		)
		(pad "12" smd rect
			(at 0.599948 -0.8001 270)
			(size 0.1778 0.6096)
			(layers "B.Cu" "B.Mask" "B.Paste")
			(net "P3V3_AUX")
		)
	)
)
